# T6G (Grand Teton) — schematic netlist excerpt (pin names and nets, part order shuffled) for the footprints in the layout excerpt that follows; sources: Cadence DE-HDL packaged netlist, KiCad conversion of 04192023_DAF0TMB3IC0_F0TG_MB_C_brd_V02_OCP.brd

PR3966  Q_RES  10 1% CHIP  pkg 0402LF  page 146 : A = P12V_AUX ; B = P12V_E1S_VCC_0
PR68  Q_RES  0 5% CHIP  pkg 0402LF  page 200 : A = VSENSE_PVDDCR_CPU1_P0_DP ; B = VSENSE_PVDDCR_CPU1_P0_VSEN0
R1483  Q_RES  4.7K 5% EMPTY  pkg 0201LF  page 309 : A = P1V8_CPU0_RT_1D ; B = JTAG_TMS_RT_CPU0_P3

(kicad_pcb
	(version 20260206)
	(generator "pcbnew")
	(generator_version "10.0")
	(general
		(thickness 1.6)
		(legacy_teardrops no)
	)
	(paper "A4")
	(title_block
		(title "04192023_DAF0TMB3IC0_F0TG_MB_C_brd_V02_OCP.brd")
		(comment 1 "Grand Teton / footprints 4218-4220 of 8354")
	)
	(layers
		(0 "F.Cu" signal "TOP")
		(4 "In1.Cu" signal "GND")
		(6 "In2.Cu" signal "IN1")
		(8 "In3.Cu" signal "GND1")
		(10 "In4.Cu" signal "IN2")
		(12 "In5.Cu" signal "GND2")
		(14 "In6.Cu" signal "IN3")
		(16 "In7.Cu" signal "GND3")
		(18 "In8.Cu" signal "VCC")
		(20 "In9.Cu" signal "VCC1")
		(22 "In10.Cu" signal "GND4")
		(24 "In11.Cu" signal "IN4")
		(26 "In12.Cu" signal "GND5")
		(28 "In13.Cu" signal "IN5")
		(30 "In14.Cu" signal "GND6")
		(32 "In15.Cu" signal "IN6")
		(34 "In16.Cu" signal "GND7")
		(2 "B.Cu" signal "BOTTOM")
		(9 "F.Adhes" user "F.Adhesive")
		(11 "B.Adhes" user "B.Adhesive")
		(13 "F.Paste" user "Package Geometry/Pastemask Top")
		(15 "B.Paste" user "Package Geometry/Pastemask Bottom")
		(5 "F.SilkS" user "Ref Des/Silkscreen Top")
		(7 "B.SilkS" user "Ref Des/Silkscreen Bottom")
		(1 "F.Mask" user "Board Geometry/Soldermask Top")
		(3 "B.Mask" user "Board Geometry/Soldermask Bottom")
		(17 "Dwgs.User" user "User.Drawings")
		(19 "Cmts.User" user "User.Comments")
		(21 "Eco1.User" user "User.Eco1")
		(23 "Eco2.User" user "User.Eco2")
		(25 "Edge.Cuts" user "Board Geometry/Outline")
		(27 "Margin" user)
		(31 "F.CrtYd" user "Package Geometry/Place Bound Top")
		(29 "B.CrtYd" user "Package Geometry/Place Bound Bottom")
		(35 "F.Fab" user "Ref Des/Assembly Top")
		(33 "B.Fab" user "Ref Des/Assembly Bottom")
	)
	(footprint ""
		(layer "F.Cu")
		(at 256.889504 -43.504612 180)
		(property "Reference" "PR3966"
			(at 0 0 180)
			(layer "F.SilkS")
			(hide yes)
			(effects
				(font
					(size 1.27 1.27)
				)
			)
		)
		(property "Value" ""
			(at 0 0 180)
			(layer "F.Fab")
			(effects
				(font
					(size 1.27 1.27)
				)
			)
		)
		(duplicate_pad_numbers_are_jumpers no)
		(fp_line
			(start 0.7874 0.4064)
			(end -0.7874 0.4064)
			(stroke
				(width 0.1524)
				(type default)
			)
			(layer "F.SilkS")
		)
		(fp_line
			(start 0.7874 -0.4064)
			(end 0.7874 0.4064)
			(stroke
				(width 0.1524)
				(type default)
			)
			(layer "F.SilkS")
		)
		(fp_line
			(start -0.7874 0.4064)
			(end -0.7874 -0.4064)
			(stroke
				(width 0.1524)
				(type default)
			)
			(layer "F.SilkS")
		)
		(fp_line
			(start -0.7874 -0.4064)
			(end 0.7874 -0.4064)
			(stroke
				(width 0.1524)
				(type default)
			)
			(layer "F.SilkS")
		)
		(fp_line
			(start 0.67945 0.3048)
			(end 0.120396 0.3048)
			(stroke
				(width 0.1)
				(type default)
			)
			(layer "F.Fab")
		)
		(fp_line
			(start 0.67945 -0.3048)
			(end 0.67945 0.3048)
			(stroke
				(width 0.1)
				(type default)
			)
			(layer "F.Fab")
		)
		(fp_line
			(start 0.12065 -0.2794)
			(end 0.12065 -0.3048)
			(stroke
				(width 0.1)
				(type default)
			)
			(layer "F.Fab")
		)
		(fp_line
			(start 0.12065 -0.3048)
			(end 0.67945 -0.3048)
			(stroke
				(width 0.1)
				(type default)
			)
			(layer "F.Fab")
		)
		(fp_line
			(start 0.120396 0.3048)
			(end 0.120396 0.2794)
			(stroke
				(width 0.1)
				(type default)
			)
			(layer "F.Fab")
		)
		(fp_line
			(start 0.120396 0.2794)
			(end -0.12065 0.2794)
			(stroke
				(width 0.1)
				(type default)
			)
			(layer "F.Fab")
		)
		(fp_line
			(start -0.12065 0.3048)
			(end -0.67945 0.3048)
			(stroke
				(width 0.1)
				(type default)
			)
			(layer "F.Fab")
		)
		(fp_line
			(start -0.12065 0.2794)
			(end -0.12065 0.3048)
			(stroke
				(width 0.1)
				(type default)
			)
			(layer "F.Fab")
		)
		(fp_line
			(start -0.12065 -0.2794)
			(end 0.12065 -0.2794)
			(stroke
				(width 0.1)
				(type default)
			)
			(layer "F.Fab")
		)
		(fp_line
			(start -0.12065 -0.305054)
			(end -0.12065 -0.2794)
			(stroke
				(width 0.1)
				(type default)
			)
			(layer "F.Fab")
		)
		(fp_line
			(start -0.67945 0.3048)
			(end -0.67945 -0.305054)
			(stroke
				(width 0.1)
				(type default)
			)
			(layer "F.Fab")
		)
		(fp_line
			(start -0.67945 -0.305054)
			(end -0.12065 -0.305054)
			(stroke
				(width 0.1)
				(type default)
			)
			(layer "F.Fab")
		)
		(pad "1" smd circle
			(at -0.40005 0 180)
			(size 0 0)
			(layers "F.Cu" "F.Mask" "F.Paste")
			(net "P12V_AUX")
		)
		(pad "2" smd circle
			(at 0.40005 0 180)
			(size 0 0)
			(layers "F.Cu" "F.Mask" "F.Paste")
			(net "P12V_E1S_VCC_0")
		)
	)
	(footprint ""
		(layer "F.Cu")
		(at 306.832 -354.457 90)
		(property "Reference" "PR68"
			(at 0 0 90)
			(layer "F.SilkS")
			(hide yes)
			(effects
				(font
					(size 1.27 1.27)
				)
			)
		)
		(property "Value" ""
			(at 0 0 90)
			(layer "F.Fab")
			(effects
				(font
					(size 1.27 1.27)
				)
			)
		)
		(duplicate_pad_numbers_are_jumpers no)
		(fp_line
			(start 0.7874 -0.4064)
			(end 0.7874 0.4064)
			(stroke
				(width 0.1524)
				(type default)
			)
			(layer "F.SilkS")
		)
		(fp_line
			(start -0.7874 -0.4064)
			(end 0.7874 -0.4064)
			(stroke
				(width 0.1524)
				(type default)
			)
			(layer "F.SilkS")
		)
		(fp_line
			(start 0.7874 0.4064)
			(end -0.7874 0.4064)
			(stroke
				(width 0.1524)
				(type default)
			)
			(layer "F.SilkS")
		)
		(fp_line
			(start -0.7874 0.4064)
			(end -0.7874 -0.4064)
			(stroke
				(width 0.1524)
				(type default)
			)
			(layer "F.SilkS")
		)
		(fp_line
			(start -0.12065 -0.305054)
			(end -0.12065 -0.2794)
			(stroke
				(width 0.1)
				(type default)
			)
			(layer "F.Fab")
		)
		(fp_line
			(start -0.67945 -0.305054)
			(end -0.12065 -0.305054)
			(stroke
				(width 0.1)
				(type default)
			)
			(layer "F.Fab")
		)
		(fp_line
			(start 0.67945 -0.3048)
			(end 0.67945 0.3048)
			(stroke
				(width 0.1)
				(type default)
			)
			(layer "F.Fab")
		)
		(fp_line
			(start 0.12065 -0.3048)
			(end 0.67945 -0.3048)
			(stroke
				(width 0.1)
				(type default)
			)
			(layer "F.Fab")
		)
		(fp_line
			(start 0.12065 -0.2794)
			(end 0.12065 -0.3048)
			(stroke
				(width 0.1)
				(type default)
			)
			(layer "F.Fab")
		)
		(fp_line
			(start -0.12065 -0.2794)
			(end 0.12065 -0.2794)
			(stroke
				(width 0.1)
				(type default)
			)
			(layer "F.Fab")
		)
		(fp_line
			(start 0.120396 0.2794)
			(end -0.12065 0.2794)
			(stroke
				(width 0.1)
				(type default)
			)
			(layer "F.Fab")
		)
		(fp_line
			(start -0.12065 0.2794)
			(end -0.12065 0.3048)
			(stroke
				(width 0.1)
				(type default)
			)
			(layer "F.Fab")
		)
		(fp_line
			(start 0.67945 0.3048)
			(end 0.120396 0.3048)
			(stroke
				(width 0.1)
				(type default)
			)
			(layer "F.Fab")
		)
		(fp_line
			(start 0.120396 0.3048)
			(end 0.120396 0.2794)
			(stroke
				(width 0.1)
				(type default)
			)
			(layer "F.Fab")
		)
		(fp_line
			(start -0.12065 0.3048)
			(end -0.67945 0.3048)
			(stroke
				(width 0.1)
				(type default)
			)
			(layer "F.Fab")
		)
		(fp_line
			(start -0.67945 0.3048)
			(end -0.67945 -0.305054)
			(stroke
				(width 0.1)
				(type default)
			)
			(layer "F.Fab")
		)
		(pad "1" smd circle
			(at -0.40005 0 90)
			(size 0 0)
			(layers "F.Cu" "F.Mask" "F.Paste")
			(net "VSENSE_PVDDCR_CPU1_P0_DP")
		)
		(pad "2" smd circle
			(at 0.40005 0 90)
			(size 0 0)
			(layers "F.Cu" "F.Mask" "F.Paste")
			(net "VSENSE_PVDDCR_CPU1_P0_VSEN0")
		)
	)
	(footprint ""
		(layer "F.Cu")
		(at 426.974 -421.64 90)
		(property "Reference" "R1483"
			(at 0 0 90)
			(layer "F.SilkS")
			(hide yes)
			(effects
				(font
					(size 1.27 1.27)
				)
			)
		)
		(property "Value" ""
			(at 0 0 90)
			(layer "F.Fab")
			(effects
				(font
					(size 1.27 1.27)
				)
			)
		)
		(duplicate_pad_numbers_are_jumpers no)
		(fp_line
			(start 0.32512 -0.175006)
			(end 0.32512 0.175006)
			(stroke
				(width 0.1)
				(type default)
			)
			(layer "F.Fab")
		)
		(fp_line
			(start -0.32512 -0.175006)
			(end 0.32512 -0.175006)
			(stroke
				(width 0.1)
				(type default)
			)
			(layer "F.Fab")
		)
		(fp_line
			(start 0.32512 0.175006)
			(end -0.32512 0.175006)
			(stroke
				(width 0.1)
				(type default)
			)
			(layer "F.Fab")
		)
		(fp_line
			(start -0.32512 0.175006)
			(end -0.32512 -0.175006)
			(stroke
				(width 0.1)
				(type default)
			)
			(layer "F.Fab")
		)
		(pad "1" smd rect
			(at -0.2667 0 90)
			(size 0.3048 0.381)
			(layers "F.Cu" "F.Mask" "F.Paste")
			(net "P1V8_CPU0_RT_1D")
		)
		(pad "2" smd rect
			(at 0.2667 0 270)
			(size 0.3048 0.381)
			(layers "F.Cu" "F.Mask" "F.Paste")
			(net "JTAG_TMS_RT_CPU0_P3")
		)
	)
)
